FILE_TYPE = CONNECTIVITY;
{Allegro Design Entry HDL 17.4-2019 S026 (4007227) 1/17/2022}
"PAGE_NUMBER" = 448;
0"NC";
1"P5E_CPU1_P2_RX_DP<15:8>";
2"P5E_CPU1_P2_RX_DP<7:0>";
3"P5E_CPU1_P2_RX_DN<7:0>";
4"P5E_CPU1_P2_RX_DN<15:8>";
5"P5E_CPU1_P2_RX_DP<15>";
6"P5E_CPU1_P2_RX_DN<15>";
7"P5E_CPU1_P2_RX_DP<14>";
8"P5E_CPU1_P2_RX_DN<14>";
9"P5E_CPU1_P2_RX_DN<11>";
10"P5E_CPU1_P2_RX_DN<12>";
11"P5E_CPU1_P2_RX_DN<9>";
12"P5E_CPU1_P2_RX_DN<8>";
13"P5E_CPU1_P2_RX_DN<13>";
14"P5E_CPU1_P2_RX_DN<10>";
15"P5E_CPU1_P2_RX_DN<3>";
16"P5E_CPU1_P2_RX_DN<0>";
17"P5E_CPU1_P2_RX_DN<1>";
18"P5E_CPU1_P2_RX_DN<6>";
19"P5E_CPU1_P2_RX_DN<5>";
20"P5E_CPU1_P2_RX_DN<4>";
21"P5E_CPU1_P2_RX_DN<2>";
22"P5E_CPU1_P2_RX_DN<7>";
23"P5E_CPU1_P2_RX_DP<5>";
24"P5E_CPU1_P2_RX_DP<6>";
25"P5E_CPU1_P2_RX_DP<0>";
26"P5E_CPU1_P2_RX_DP<1>";
27"P5E_CPU1_P2_RX_DP<2>";
28"P5E_CPU1_P2_RX_DP<4>";
29"P5E_CPU1_P2_RX_DP<7>";
30"P5E_CPU1_P2_RX_DP<3>";
31"P5E_CPU1_P2_RX_DP<13>";
32"P5E_CPU1_P2_RX_DP<12>";
33"P5E_CPU1_P2_RX_DP<11>";
34"P5E_CPU1_P2_RX_DP<8>";
35"P5E_CPU1_P2_RX_DP<9>";
36"P5E_CPU1_P2_RX_DP<10>";
%"PT5161LRS"
"6","(-7700,4375)","0","pure_quanta","I1";
;
LOCATION"U6016"
$SEC"6"
CDS_SEC"6"
MATERIAL"IC"
PART_TYPE"SMLF"
VALUE"PT5161LRS"
CDS_LIB"pure_quanta"
CDS_LMAN_SYM_OUTLINE"-350,1450,300,-1400"
NEEDS_NO_SIZE"TRUE"
PART_NUMBER"AJ051610U03";
"A_PETN7"
$PN"CC29"12;
"A_PETP7"
$PN"CA26"34;
"A_PETN6"
$PN"BT29"11;
"A_PETP6"
$PN"BP26"35;
"A_PETN5"
$PN"BJ29"14;
"A_PETP5"
$PN"BG26"36;
"A_PETN4"
$PN"BB29"9;
"A_PETP4"
$PN"AY26"33;
"A_PETN3"
$PN"AR29"10;
"A_PETP3"
$PN"AN26"32;
"A_PETN2"
$PN"AH29"13;
"A_PETP2"
$PN"AF26"31;
"A_PETN1"
$PN"AA29"8;
"A_PETP1"
$PN"W26"7;
"A_PETN0"
$PN"P29"6;
"A_PETP0"
$PN"M26"5;
%"TAP"
"1","(-6475,4475)","0","standard","I10";
;
CDS_LIB"standard"
BODY_TYPE"PLUMBING"
HDL_TAP"TRUE";
"B \NAC \NWC"4;
"S \NAC"
BN"12"10;
%"TAP"
"1","(-6675,4575)","0","standard","I11";
;
CDS_LIB"standard"
BODY_TYPE"PLUMBING"
HDL_TAP"TRUE";
"B \NAC \NWC"1;
"S \NAC"
BN"12"32;
%"TAP"
"1","(-6675,4925)","0","standard","I12";
;
CDS_LIB"standard"
BODY_TYPE"PLUMBING"
HDL_TAP"TRUE";
"B \NAC \NWC"1;
"S \NAC"
BN"13"31;
%"TAP"
"1","(-6475,4825)","0","standard","I13";
;
CDS_LIB"standard"
BODY_TYPE"PLUMBING"
HDL_TAP"TRUE";
"B \NAC \NWC"4;
"S \NAC"
BN"13"13;
%"TAP"
"1","(-6675,5275)","0","standard","I14";
;
CDS_LIB"standard"
BODY_TYPE"PLUMBING"
HDL_TAP"TRUE";
"B \NAC \NWC"1;
"S \NAC"
BN"14"7;
%"TAP"
"1","(-6475,5175)","0","standard","I15";
;
CDS_LIB"standard"
BODY_TYPE"PLUMBING"
HDL_TAP"TRUE";
"B \NAC \NWC"4;
"S \NAC"
BN"14"8;
%"TAP"
"1","(-6475,5525)","0","standard","I16";
;
CDS_LIB"standard"
BODY_TYPE"PLUMBING"
HDL_TAP"TRUE";
"B \NAC \NWC"4;
"S \NAC"
BN"15"6;
%"TAP"
"1","(-6675,5625)","0","standard","I17";
;
CDS_LIB"standard"
BODY_TYPE"PLUMBING"
HDL_TAP"TRUE";
"B \NAC \NWC"1;
"S \NAC"
BN"15"5;
%"TAP"
"1","(-6675,3525)","0","standard","I2";
;
CDS_LIB"standard"
BODY_TYPE"PLUMBING"
HDL_TAP"TRUE";
"B \NAC \NWC"1;
"S \NAC"
BN"9"35;
%"TAP"
"1","(-2150,3250)","0","standard","I20";
;
CDS_LIB"standard"
BODY_TYPE"PLUMBING"
HDL_TAP"TRUE";
"B \NAC \NWC"2;
"S \NAC"
BN"0"25;
%"TAP"
"1","(-2150,4300)","0","standard","I21";
;
CDS_LIB"standard"
BODY_TYPE"PLUMBING"
HDL_TAP"TRUE";
"B \NAC \NWC"2;
"S \NAC"
BN"3"30;
%"TAP"
"1","(-2150,3950)","0","standard","I22";
;
CDS_LIB"standard"
BODY_TYPE"PLUMBING"
HDL_TAP"TRUE";
"B \NAC \NWC"2;
"S \NAC"
BN"2"27;
%"TAP"
"1","(-2150,3600)","0","standard","I23";
;
CDS_LIB"standard"
BODY_TYPE"PLUMBING"
HDL_TAP"TRUE";
"B \NAC \NWC"2;
"S \NAC"
BN"1"26;
%"TAP"
"1","(-1950,3150)","0","standard","I24";
;
CDS_LIB"standard"
BODY_TYPE"PLUMBING"
HDL_TAP"TRUE";
"B \NAC \NWC"3;
"S \NAC"
BN"0"16;
%"TAP"
"1","(-1950,3500)","0","standard","I25";
;
CDS_LIB"standard"
BODY_TYPE"PLUMBING"
HDL_TAP"TRUE";
"B \NAC \NWC"3;
"S \NAC"
BN"1"17;
%"TAP"
"1","(-1950,3850)","0","standard","I26";
;
CDS_LIB"standard"
BODY_TYPE"PLUMBING"
HDL_TAP"TRUE";
"B \NAC \NWC"3;
"S \NAC"
BN"2"21;
%"TAP"
"1","(-1950,4200)","0","standard","I27";
;
CDS_LIB"standard"
BODY_TYPE"PLUMBING"
HDL_TAP"TRUE";
"B \NAC \NWC"3;
"S \NAC"
BN"3"15;
%"TAP"
"1","(-1950,4550)","0","standard","I28";
;
CDS_LIB"standard"
BODY_TYPE"PLUMBING"
HDL_TAP"TRUE";
"B \NAC \NWC"3;
"S \NAC"
BN"4"20;
%"TAP"
"1","(-2150,4650)","0","standard","I29";
;
CDS_LIB"standard"
BODY_TYPE"PLUMBING"
HDL_TAP"TRUE";
"B \NAC \NWC"2;
"S \NAC"
BN"4"28;
%"TAP"
"1","(-6675,3175)","0","standard","I3";
;
CDS_LIB"standard"
BODY_TYPE"PLUMBING"
HDL_TAP"TRUE";
"B \NAC \NWC"1;
"S \NAC"
BN"8"34;
%"TAP"
"1","(-2150,5000)","0","standard","I30";
;
CDS_LIB"standard"
BODY_TYPE"PLUMBING"
HDL_TAP"TRUE";
"B \NAC \NWC"2;
"S \NAC"
BN"5"23;
%"TAP"
"1","(-2150,5350)","0","standard","I31";
;
CDS_LIB"standard"
BODY_TYPE"PLUMBING"
HDL_TAP"TRUE";
"B \NAC \NWC"2;
"S \NAC"
BN"6"24;
%"TAP"
"1","(-2150,5700)","0","standard","I32";
;
CDS_LIB"standard"
BODY_TYPE"PLUMBING"
HDL_TAP"TRUE";
"B \NAC \NWC"2;
"S \NAC"
BN"7"29;
%"TAP"
"1","(-1950,4900)","0","standard","I33";
;
CDS_LIB"standard"
BODY_TYPE"PLUMBING"
HDL_TAP"TRUE";
"B \NAC \NWC"3;
"S \NAC"
BN"5"19;
%"TAP"
"1","(-1950,5600)","0","standard","I34";
;
CDS_LIB"standard"
BODY_TYPE"PLUMBING"
HDL_TAP"TRUE";
"B \NAC \NWC"3;
"S \NAC"
BN"7"22;
%"TAP"
"1","(-1950,5250)","0","standard","I37";
;
CDS_LIB"standard"
BODY_TYPE"PLUMBING"
HDL_TAP"TRUE";
"B \NAC \NWC"3;
"S \NAC"
BN"6"18;
%"PT5161LRS"
"7","(-3175,4450)","0","pure_quanta","I38";
;
LOCATION"U6016"
$SEC"7"
CDS_SEC"7"
PART_TYPE"SMLF"
VALUE"PT5161LRS"
MATERIAL"IC"
NEEDS_NO_SIZE"TRUE"
CDS_LMAN_SYM_OUTLINE"-350,1450,300,-1400"
CDS_LIB"pure_quanta"
PART_NUMBER"AJ051610U03";
"A_PETN15"
$PN"EW29"16;
"A_PETP15"
$PN"EU26"25;
"A_PETN14"
$PN"EM29"17;
"A_PETP14"
$PN"EK26"26;
"A_PETN13"
$PN"EE29"21;
"A_PETP13"
$PN"EC26"27;
"A_PETN12"
$PN"DV29"15;
"A_PETP12"
$PN"DT26"30;
"A_PETN11"
$PN"DL29"20;
"A_PETP11"
$PN"DJ26"28;
"A_PETN10"
$PN"DD29"19;
"A_PETP10"
$PN"DB26"23;
"A_PETN9"
$PN"CU29"18;
"A_PETP9"
$PN"CR26"24;
"A_PETN8"
$PN"CK29"22;
"A_PETP8"
$PN"CH26"29;
%"TAP"
"1","(-6475,3075)","0","standard","I4";
;
CDS_LIB"standard"
BODY_TYPE"PLUMBING"
HDL_TAP"TRUE";
"B \NAC \NWC"4;
"S \NAC"
BN"8"12;
%"TAP"
"1","(-6475,3425)","0","standard","I5";
;
CDS_LIB"standard"
BODY_TYPE"PLUMBING"
HDL_TAP"TRUE";
"B \NAC \NWC"4;
"S \NAC"
BN"9"11;
%"TAP"
"1","(-6675,3875)","0","standard","I6";
;
CDS_LIB"standard"
BODY_TYPE"PLUMBING"
HDL_TAP"TRUE";
"B \NAC \NWC"1;
"S \NAC"
BN"10"36;
%"TAP"
"1","(-6475,3775)","0","standard","I7";
;
CDS_LIB"standard"
BODY_TYPE"PLUMBING"
HDL_TAP"TRUE";
"B \NAC \NWC"4;
"S \NAC"
BN"10"14;
%"TAP"
"1","(-6675,4225)","0","standard","I8";
;
CDS_LIB"standard"
BODY_TYPE"PLUMBING"
HDL_TAP"TRUE";
"B \NAC \NWC"1;
"S \NAC"
BN"11"33;
%"TAP"
"1","(-6475,4125)","0","standard","I9";
;
CDS_LIB"standard"
BODY_TYPE"PLUMBING"
HDL_TAP"TRUE";
"B \NAC \NWC"4;
"S \NAC"
BN"11"9;
END.
